# BASEBOARD_FAB2 (Tioga Pass) — schematic netlist excerpt (pin names and nets, part order shuffled) for the footprints in the layout excerpt that follows; sources: Cadence DE-HDL packaged netlist, KiCad conversion of Wiwynn_Tioga_Pass_MB.brd

C2L52  CAP_A  0.01UF 25V 10% X7R  pkg 0402V  page 172 : A = SATA6G_S1_TX_C_DP ; B = SATA6G_S1_TX_DP
R9G32  RES  0.0 5% CHIP  pkg 0402  page 152 : A = H_CPU1_GHJ_MEMHOT_LVT3_R_N ; B = H_CPU1_MEMGHJ_MEMHOT_LVT3_K_N
C1T7  CAP  10UF 6.3V 20% X6S  pkg 0603  page 239 : A = P3V3_STBY ; B = GND

(kicad_pcb
	(version 20260206)
	(generator "pcbnew")
	(generator_version "10.0")
	(general
		(thickness 1.6)
		(legacy_teardrops no)
	)
	(paper "A4")
	(title_block
		(title "Wiwynn_Tioga_Pass_MB.brd")
		(comment 1 "Tioga Pass / footprints 2766-2768 of 4770")
	)
	(layers
		(0 "F.Cu" signal "TOP")
		(4 "In1.Cu" signal "L2GND")
		(6 "In2.Cu" signal "L3")
		(8 "In3.Cu" signal "L4GND")
		(10 "In4.Cu" signal "L5")
		(12 "In5.Cu" signal "L6GND")
		(14 "In6.Cu" signal "L7VCC")
		(16 "In7.Cu" signal "L8VCC")
		(18 "In8.Cu" signal "L9GND")
		(20 "In9.Cu" signal "L10")
		(22 "In10.Cu" signal "L11GND")
		(24 "In11.Cu" signal "L12")
		(26 "In12.Cu" signal "L13GND")
		(2 "B.Cu" signal "BOTTOM")
		(9 "F.Adhes" user "F.Adhesive")
		(11 "B.Adhes" user "B.Adhesive")
		(13 "F.Paste" user "Package Geometry/Pastemask Top")
		(15 "B.Paste" user "Package Geometry/Pastemask Bottom")
		(5 "F.SilkS" user "Ref Des/Silkscreen Top")
		(7 "B.SilkS" user "Ref Des/Silkscreen Bottom")
		(1 "F.Mask" user "Board Geometry/Soldermask Top")
		(3 "B.Mask" user "Board Geometry/Soldermask Bottom")
		(17 "Dwgs.User" user "User.Drawings")
		(19 "Cmts.User" user "User.Comments")
		(21 "Eco1.User" user "User.Eco1")
		(23 "Eco2.User" user "User.Eco2")
		(25 "Edge.Cuts" user "Board Geometry/Outline")
		(27 "Margin" user)
		(31 "F.CrtYd" user "Package Geometry/Place Bound Top")
		(29 "B.CrtYd" user "Package Geometry/Place Bound Bottom")
		(35 "F.Fab" user "Ref Des/Assembly Top")
		(33 "B.Fab" user "Ref Des/Assembly Bottom")
	)
	(footprint ""
		(layer "B.Cu")
		(at 430.726088 -15.280894 -90)
		(property "Reference" "R9G32"
			(at 0 0 90)
			(layer "B.SilkS")
			(hide yes)
			(effects
				(font
					(size 1.27 1.27)
				)
				(justify mirror)
			)
		)
		(property "Value" ""
			(at 0 0 90)
			(layer "B.Fab")
			(effects
				(font
					(size 1.27 1.27)
				)
				(justify mirror)
			)
		)
		(duplicate_pad_numbers_are_jumpers no)
		(fp_poly
			(pts
				(xy 0.2794 -0.1016) (xy -0.2794 -0.1016) (xy -0.2794 0.9906) (xy 0.2794 0.9906)
			)
			(stroke
				(width 0)
				(type default)
			)
			(fill no)
			(layer "B.CrtYd")
		)
		(fp_line
			(start -0.2794 0.9906)
			(end -0.2794 -0.1016)
			(stroke
				(width 0.1)
				(type default)
			)
			(layer "B.Fab")
		)
		(fp_line
			(start 0.2794 0.9906)
			(end -0.2794 0.9906)
			(stroke
				(width 0.1)
				(type default)
			)
			(layer "B.Fab")
		)
		(fp_line
			(start -0.2794 -0.1016)
			(end 0.2794 -0.1016)
			(stroke
				(width 0.1)
				(type default)
			)
			(layer "B.Fab")
		)
		(fp_line
			(start 0.2794 -0.1016)
			(end 0.2794 0.9906)
			(stroke
				(width 0.1)
				(type default)
			)
			(layer "B.Fab")
		)
		(pad "1" smd rect
			(at 0 0 90)
			(size 0.508 0.508)
			(layers "B.Cu" "B.Mask" "B.Paste")
			(net "H_CPU1_GHJ_MEMHOT_LVT3_R_N")
		)
		(pad "2" smd rect
			(at 0 0.889 90)
			(size 0.508 0.508)
			(layers "B.Cu" "B.Mask" "B.Paste")
			(net "H_CPU1_MEMGHJ_MEMHOT_LVT3_K_N")
		)
		(zone
			(layer "B.Cu")
			(hatch none 0.5)
			(connect_pads
				(clearance 0)
			)
			(min_thickness 0.25)
			(keepout
				(tracks not_allowed)
				(vias allowed)
				(pads allowed)
				(copperpour not_allowed)
				(footprints allowed)
			)
			(placement
				(enabled no)
				(sheetname "")
			)
			(fill
				(thermal_gap 0.5)
				(thermal_bridge_width 0.5)
				(island_removal_mode 0)
			)
			(polygon
				(pts
					(xy 430.091088 -15.026894) (xy 430.091088 -15.534894) (xy 430.472088 -15.534894) (xy 430.472088 -15.026894)
				)
			)
		)
		(zone
			(layer "B.Cu")
			(hatch none 0.5)
			(connect_pads
				(clearance 0)
			)
			(min_thickness 0.25)
			(keepout
				(tracks allowed)
				(vias not_allowed)
				(pads allowed)
				(copperpour not_allowed)
				(footprints allowed)
			)
			(placement
				(enabled no)
				(sheetname "")
			)
			(fill
				(thermal_gap 0.5)
				(thermal_bridge_width 0.5)
				(island_removal_mode 0)
			)
			(polygon
				(pts
					(xy 430.472088 -15.026894) (xy 430.472088 -15.534894) (xy 430.091088 -15.534894) (xy 430.091088 -15.026894)
				)
			)
		)
	)
	(footprint ""
		(layer "B.Cu")
		(at 430.85512 -141.939518 90)
		(property "Reference" "C2L52"
			(at 0 0 90)
			(layer "B.SilkS")
			(hide yes)
			(effects
				(font
					(size 1.27 1.27)
				)
				(justify mirror)
			)
		)
		(property "Value" ""
			(at 0 0 90)
			(layer "B.Fab")
			(effects
				(font
					(size 1.27 1.27)
				)
				(justify mirror)
			)
		)
		(duplicate_pad_numbers_are_jumpers no)
		(fp_poly
			(pts
				(xy -0.3048 -0.1016) (xy -0.3048 0.9906) (xy 0.3048 0.9906) (xy 0.3048 -0.1016)
			)
			(stroke
				(width 0)
				(type default)
			)
			(fill no)
			(layer "B.CrtYd")
		)
		(fp_line
			(start 0.3048 -0.1016)
			(end 0.3048 0.9906)
			(stroke
				(width 0.1)
				(type default)
			)
			(layer "B.Fab")
		)
		(fp_line
			(start -0.3048 -0.1016)
			(end 0.3048 -0.1016)
			(stroke
				(width 0.1)
				(type default)
			)
			(layer "B.Fab")
		)
		(fp_line
			(start 0.3048 0.9906)
			(end -0.3048 0.9906)
			(stroke
				(width 0.1)
				(type default)
			)
			(layer "B.Fab")
		)
		(fp_line
			(start -0.3048 0.9906)
			(end -0.3048 -0.1016)
			(stroke
				(width 0.1)
				(type default)
			)
			(layer "B.Fab")
		)
		(pad "1" smd rect
			(at 0 0 270)
			(size 0.508 0.508)
			(layers "B.Cu" "B.Mask" "B.Paste")
			(net "SATA6G_S1_TX_C_DP")
		)
		(pad "2" smd rect
			(at 0 0.889 270)
			(size 0.508 0.508)
			(layers "B.Cu" "B.Mask" "B.Paste")
			(net "SATA6G_S1_TX_DP")
		)
		(zone
			(layer "B.Cu")
			(hatch none 0.5)
			(connect_pads
				(clearance 0)
			)
			(min_thickness 0.25)
			(keepout
				(tracks allowed)
				(vias not_allowed)
				(pads allowed)
				(copperpour not_allowed)
				(footprints allowed)
			)
			(placement
				(enabled no)
				(sheetname "")
			)
			(fill
				(thermal_gap 0.5)
				(thermal_bridge_width 0.5)
				(island_removal_mode 0)
			)
			(polygon
				(pts
					(xy 431.10912 -142.193518) (xy 431.10912 -141.685518) (xy 431.49012 -141.685518) (xy 431.49012 -142.193518)
				)
			)
		)
		(zone
			(layer "B.Cu")
			(hatch none 0.5)
			(connect_pads
				(clearance 0)
			)
			(min_thickness 0.25)
			(keepout
				(tracks not_allowed)
				(vias allowed)
				(pads allowed)
				(copperpour not_allowed)
				(footprints allowed)
			)
			(placement
				(enabled no)
				(sheetname "")
			)
			(fill
				(thermal_gap 0.5)
				(thermal_bridge_width 0.5)
				(island_removal_mode 0)
			)
			(polygon
				(pts
					(xy 431.49012 -142.193518) (xy 431.49012 -141.685518) (xy 431.10912 -141.685518) (xy 431.10912 -142.193518)
				)
			)
		)
	)
	(footprint ""
		(layer "B.Cu")
		(at 468.2744 -41.5798)
		(property "Reference" "C1T7"
			(at 0 0 0)
			(layer "B.SilkS")
			(hide yes)
			(effects
				(font
					(size 1.27 1.27)
				)
				(justify mirror)
			)
		)
		(property "Value" ""
			(at 0 0 0)
			(layer "B.Fab")
			(effects
				(font
					(size 1.27 1.27)
				)
				(justify mirror)
			)
		)
		(duplicate_pad_numbers_are_jumpers no)
		(fp_poly
			(pts
				(xy 0.4953 -0.2032) (xy -0.4953 -0.2032) (xy -0.4953 1.6002) (xy 0.4953 1.6002)
			)
			(stroke
				(width 0)
				(type default)
			)
			(fill no)
			(layer "B.CrtYd")
		)
		(fp_line
			(start -0.4953 -0.2032)
			(end -0.4953 1.6002)
			(stroke
				(width 0.1)
				(type default)
			)
			(layer "B.Fab")
		)
		(fp_line
			(start -0.4953 1.6002)
			(end 0.4953 1.6002)
			(stroke
				(width 0.1)
				(type default)
			)
			(layer "B.Fab")
		)
		(fp_line
			(start 0.4953 -0.2032)
			(end -0.4953 -0.2032)
			(stroke
				(width 0.1)
				(type default)
			)
			(layer "B.Fab")
		)
		(fp_line
			(start 0.4953 1.6002)
			(end 0.4953 -0.2032)
			(stroke
				(width 0.1)
				(type default)
			)
			(layer "B.Fab")
		)
		(pad "1" smd rect
			(at 0 0 180)
			(size 0.762 0.889)
			(layers "B.Cu" "B.Mask" "B.Paste")
			(net "P3V3_STBY")
		)
		(pad "2" smd rect
			(at 0 1.397 180)
			(size 0.762 0.889)
			(layers "B.Cu" "B.Mask" "B.Paste")
			(net "GND")
		)
		(zone
			(layer "B.Cu")
			(hatch none 0.5)
			(connect_pads
				(clearance 0)
			)
			(min_thickness 0.25)
			(keepout
				(tracks not_allowed)
				(vias allowed)
				(pads allowed)
				(copperpour not_allowed)
				(footprints allowed)
			)
			(placement
				(enabled no)
				(sheetname "")
			)
			(fill
				(thermal_gap 0.5)
				(thermal_bridge_width 0.5)
				(island_removal_mode 0)
			)
			(polygon
				(pts
					(xy 468.6554 -41.1353) (xy 467.8934 -41.1353) (xy 467.8934 -40.6273) (xy 468.6554 -40.6273)
				)
			)
		)
	)
)
